(kicad_pcb
	(version 20260206)
	(generator "pcbnew")
	(generator_version "10.0")
	(general
		(thickness 1.6)
		(legacy_teardrops no)
	)
	(paper "A4")
	(title_block
		(title "fcb — 12433-1M.1206WZS1330.brd")
		(comment 1 "Open Vault / Knox (Wiwynn) / footprints 448-452 of 495")
	)
	(layers
		(0 "F.Cu" signal "TOP")
		(4 "In1.Cu" signal "L2GND")
		(6 "In2.Cu" signal "L3VCC")
		(2 "B.Cu" signal "BOTTOM")
		(9 "F.Adhes" user "F.Adhesive")
		(11 "B.Adhes" user "B.Adhesive")
		(13 "F.Paste" user "Package Geometry/Pastemask Top")
		(15 "B.Paste" user "Package Geometry/Pastemask Bottom")
		(5 "F.SilkS" user "Ref Des/Silkscreen Top")
		(7 "B.SilkS" user "Ref Des/Silkscreen Bottom")
		(1 "F.Mask" user "Board Geometry/Soldermask Top")
		(3 "B.Mask" user "Board Geometry/Soldermask Bottom")
		(17 "Dwgs.User" user "User.Drawings")
		(19 "Cmts.User" user "User.Comments")
		(21 "Eco1.User" user "User.Eco1")
		(23 "Eco2.User" user "User.Eco2")
		(25 "Edge.Cuts" user "Board Geometry/Outline")
		(27 "Margin" user)
		(31 "F.CrtYd" user "Package Geometry/Place Bound Top")
		(29 "B.CrtYd" user "Package Geometry/Place Bound Bottom")
		(35 "F.Fab" user "Ref Des/Assembly Top")
		(33 "B.Fab" user "Ref Des/Assembly Bottom")
	)
	(footprint ""
		(layer "F.Cu")
		(at 20.3454 -481.5586)
		(property "Reference" "R177"
			(at 0 0 0)
			(layer "F.SilkS")
			(hide yes)
			(effects
				(font
					(size 1.27 1.27)
				)
			)
		)
		(property "Value" "0R1206-PAD-1-GP"
			(at 0 -5.0292 0)
			(unlocked yes)
			(layer "F.Fab")
			(hide yes)
			(effects
				(font
					(size 1.016 1.016)
					(thickness 0.1524)
				)
			)
		)
		(property "Device Type" "0R1206-PAD-1"
			(at 0 -6.5532 0)
			(unlocked yes)
			(layer "F.Fab")
			(hide yes)
			(effects
				(font
					(size 1.016 1.016)
					(thickness 0.1524)
				)
			)
		)
		(duplicate_pad_numbers_are_jumpers no)
		(fp_line
			(start -1.016 -2.2352)
			(end -1.016 2.2352)
			(stroke
				(width 0.1524)
				(type default)
			)
			(layer "F.SilkS")
		)
		(fp_line
			(start -1.016 2.2352)
			(end 1.016 2.2352)
			(stroke
				(width 0.1524)
				(type default)
			)
			(layer "F.SilkS")
		)
		(fp_line
			(start 1.016 -2.2352)
			(end -1.016 -2.2352)
			(stroke
				(width 0.1524)
				(type default)
			)
			(layer "F.SilkS")
		)
		(fp_line
			(start 1.016 2.2352)
			(end 1.016 -2.2352)
			(stroke
				(width 0.1524)
				(type default)
			)
			(layer "F.SilkS")
		)
		(fp_rect
			(start -1.0922 2.3114)
			(end 1.0922 -2.3114)
			(stroke
				(width 0)
				(type default)
			)
			(fill no)
			(layer "F.CrtYd")
		)
		(fp_poly
			(pts
				(xy -1.0922 -2.3114) (xy 1.0922 -2.3114) (xy 1.0922 2.3114) (xy -1.0922 2.3114)
			)
			(stroke
				(width 0)
				(type default)
			)
			(fill no)
			(layer "F.Fab")
		)
		(pad "1" smd rect
			(at 0 -1.397)
			(size 1.651 2.0574)
			(drill
				(offset 0 0.3937)
			)
			(layers "F.Cu" "F.Mask" "F.Paste")
			(net "P12V_FAN1")
		)
		(pad "2" smd rect
			(at 0 1.397)
			(size 1.651 2.0574)
			(drill
				(offset 0 -0.3937)
			)
			(layers "F.Cu" "F.Mask" "F.Paste")
			(net "P12V")
		)
	)
	(footprint ""
		(layer "F.Cu")
		(at 38.43909 -161.068766 180)
		(property "Reference" "R5"
			(at 0 0 180)
			(layer "F.SilkS")
			(hide yes)
			(effects
				(font
					(size 1.27 1.27)
				)
			)
		)
		(property "Value" "0R2J-2-GP"
			(at 0.064008 -3.993896 180)
			(unlocked yes)
			(layer "F.Fab")
			(hide yes)
			(effects
				(font
					(size 1.016 1.016)
					(thickness 0.1524)
				)
			)
		)
		(property "Device Type" "R402H16"
			(at 0.064008 -5.517896 180)
			(unlocked yes)
			(layer "F.Fab")
			(hide yes)
			(effects
				(font
					(size 1.016 1.016)
					(thickness 0.1524)
				)
			)
		)
		(duplicate_pad_numbers_are_jumpers no)
		(fp_line
			(start 0.508 -0.9398)
			(end -0.508 -0.9398)
			(stroke
				(width 0.1524)
				(type default)
			)
			(layer "F.SilkS")
		)
		(fp_line
			(start -0.508 -0.9398)
			(end -0.508 0.9398)
			(stroke
				(width 0.1524)
				(type default)
			)
			(layer "F.SilkS")
		)
		(fp_rect
			(start -0.508 0.9398)
			(end 0.508 -0.9398)
			(stroke
				(width 0)
				(type default)
			)
			(fill no)
			(layer "F.CrtYd")
		)
		(fp_rect
			(start -0.508 0.9398)
			(end 0.508 -0.9398)
			(stroke
				(width 0)
				(type default)
			)
			(fill no)
			(layer "F.Fab")
		)
		(pad "1" smd custom
			(at 0 -0.4445 180)
			(size 0.1397 0.1397)
			(layers "F.Cu" "F.Mask" "F.Paste")
			(net "NCT7904_CLKIN")
			(options
				(clearance outline)
				(anchor circle)
			)
			(primitives
				(gr_poly
					(pts
						(arc
							(start -0.1778 -0.2794)
							(mid -0.249642 -0.249642)
							(end -0.2794 -0.1778)
						)
						(arc
							(start -0.2794 0.1778)
							(mid -0.249642 0.249642)
							(end -0.1778 0.2794)
						)
						(arc
							(start 0.1778 0.2794)
							(mid 0.249642 0.249642)
							(end 0.2794 0.1778)
						)
						(arc
							(start 0.2794 -0.1778)
							(mid 0.249642 -0.249642)
							(end 0.1778 -0.2794)
						)
					)
					(width 0)
					(fill yes)
				)
			)
		)
		(pad "2" smd custom
			(at 0 0.4445 180)
			(size 0.1397 0.1397)
			(layers "F.Cu" "F.Mask" "F.Paste")
			(net "NCT7904_CLK")
			(options
				(clearance outline)
				(anchor circle)
			)
			(primitives
				(gr_poly
					(pts
						(arc
							(start -0.1778 -0.2794)
							(mid -0.249642 -0.249642)
							(end -0.2794 -0.1778)
						)
						(arc
							(start -0.2794 0.1778)
							(mid -0.249642 0.249642)
							(end -0.1778 0.2794)
						)
						(arc
							(start 0.1778 0.2794)
							(mid 0.249642 0.249642)
							(end 0.2794 0.1778)
						)
						(arc
							(start 0.2794 -0.1778)
							(mid 0.249642 -0.249642)
							(end 0.1778 -0.2794)
						)
					)
					(width 0)
					(fill yes)
				)
			)
		)
	)
	(footprint ""
		(layer "F.Cu")
		(at 37.846508 -282.993338)
		(property "Reference" "C47"
			(at 0 0 0)
			(layer "F.SilkS")
			(hide yes)
			(effects
				(font
					(size 1.27 1.27)
				)
			)
		)
		(property "Value" "SCD1U50V3KX-GP"
			(at 0 -2.8194 0)
			(unlocked yes)
			(layer "F.Fab")
			(hide yes)
			(effects
				(font
					(size 1.016 1.016)
					(thickness 0.1524)
				)
			)
		)
		(property "Device Type" "C603H36"
			(at 0 -4.3434 0)
			(unlocked yes)
			(layer "F.Fab")
			(hide yes)
			(effects
				(font
					(size 1.016 1.016)
					(thickness 0.1524)
				)
			)
		)
		(duplicate_pad_numbers_are_jumpers no)
		(fp_line
			(start 0.508 0)
			(end -0.508 0)
			(stroke
				(width 0.2032)
				(type default)
			)
			(layer "F.SilkS")
		)
		(fp_rect
			(start -0.5842 1.3335)
			(end 0.5842 -1.3335)
			(stroke
				(width 0)
				(type default)
			)
			(fill no)
			(layer "F.CrtYd")
		)
		(fp_rect
			(start -0.5842 1.3335)
			(end 0.5842 -1.3335)
			(stroke
				(width 0)
				(type default)
			)
			(fill no)
			(layer "F.Fab")
		)
		(pad "1" smd custom
			(at 0 -0.762)
			(size 0.2159 0.2159)
			(layers "F.Cu" "F.Mask" "F.Paste")
			(net "P12V")
			(options
				(clearance outline)
				(anchor circle)
			)
			(primitives
				(gr_poly
					(pts
						(arc
							(start -0.3302 -0.4318)
							(mid -0.402042 -0.402042)
							(end -0.4318 -0.3302)
						)
						(arc
							(start -0.4318 0.3302)
							(mid -0.402042 0.402042)
							(end -0.3302 0.4318)
						)
						(arc
							(start 0.3302 0.4318)
							(mid 0.402042 0.402042)
							(end 0.4318 0.3302)
						)
						(arc
							(start 0.4318 -0.3302)
							(mid 0.402042 -0.402042)
							(end 0.3302 -0.4318)
						)
					)
					(width 0)
					(fill yes)
				)
			)
		)
		(pad "2" smd custom
			(at 0 0.762)
			(size 0.2159 0.2159)
			(layers "F.Cu" "F.Mask" "F.Paste")
			(net "GND")
			(options
				(clearance outline)
				(anchor circle)
			)
			(primitives
				(gr_poly
					(pts
						(arc
							(start -0.3302 -0.4318)
							(mid -0.402042 -0.402042)
							(end -0.4318 -0.3302)
						)
						(arc
							(start -0.4318 0.3302)
							(mid -0.402042 0.402042)
							(end -0.3302 0.4318)
						)
						(arc
							(start 0.3302 0.4318)
							(mid 0.402042 0.402042)
							(end 0.4318 0.3302)
						)
						(arc
							(start 0.4318 -0.3302)
							(mid 0.402042 -0.402042)
							(end 0.3302 -0.4318)
						)
					)
					(width 0)
					(fill yes)
				)
			)
		)
	)
	(footprint ""
		(layer "F.Cu")
		(at 17.526 -16.129 -90)
		(property "Reference" "R65"
			(at 0 0 270)
			(layer "F.SilkS")
			(hide yes)
			(effects
				(font
					(size 1.27 1.27)
				)
			)
		)
		(property "Value" "4K7R2F-GP"
			(at 0.064008 -3.993896 270)
			(unlocked yes)
			(layer "F.Fab")
			(hide yes)
			(effects
				(font
					(size 1.016 1.016)
					(thickness 0.1524)
				)
			)
		)
		(property "Device Type" "R402H16"
			(at 0.064008 -5.517896 270)
			(unlocked yes)
			(layer "F.Fab")
			(hide yes)
			(effects
				(font
					(size 1.016 1.016)
					(thickness 0.1524)
				)
			)
		)
		(duplicate_pad_numbers_are_jumpers no)
		(fp_line
			(start -0.508 -0.9398)
			(end -0.508 0.9398)
			(stroke
				(width 0.1524)
				(type default)
			)
			(layer "F.SilkS")
		)
		(fp_line
			(start 0.508 -0.9398)
			(end -0.508 -0.9398)
			(stroke
				(width 0.1524)
				(type default)
			)
			(layer "F.SilkS")
		)
		(fp_rect
			(start -0.508 0.9398)
			(end 0.508 -0.9398)
			(stroke
				(width 0)
				(type default)
			)
			(fill no)
			(layer "F.CrtYd")
		)
		(fp_rect
			(start -0.508 0.9398)
			(end 0.508 -0.9398)
			(stroke
				(width 0)
				(type default)
			)
			(fill no)
			(layer "F.Fab")
		)
		(pad "1" smd custom
			(at 0 -0.4445 270)
			(size 0.1397 0.1397)
			(layers "F.Cu" "F.Mask" "F.Paste")
			(net "P12V")
			(options
				(clearance outline)
				(anchor circle)
			)
			(primitives
				(gr_poly
					(pts
						(arc
							(start -0.1778 -0.2794)
							(mid -0.249642 -0.249642)
							(end -0.2794 -0.1778)
						)
						(arc
							(start -0.2794 0.1778)
							(mid -0.249642 0.249642)
							(end -0.1778 0.2794)
						)
						(arc
							(start 0.1778 0.2794)
							(mid 0.249642 0.249642)
							(end 0.2794 0.1778)
						)
						(arc
							(start 0.2794 -0.1778)
							(mid 0.249642 -0.249642)
							(end 0.1778 -0.2794)
						)
					)
					(width 0)
					(fill yes)
				)
			)
		)
		(pad "2" smd custom
			(at 0 0.4445 270)
			(size 0.1397 0.1397)
			(layers "F.Cu" "F.Mask" "F.Paste")
			(net "PWM_OUT_FAN6_NET")
			(options
				(clearance outline)
				(anchor circle)
			)
			(primitives
				(gr_poly
					(pts
						(arc
							(start -0.1778 -0.2794)
							(mid -0.249642 -0.249642)
							(end -0.2794 -0.1778)
						)
						(arc
							(start -0.2794 0.1778)
							(mid -0.249642 0.249642)
							(end -0.1778 0.2794)
						)
						(arc
							(start 0.1778 0.2794)
							(mid 0.249642 0.249642)
							(end 0.2794 0.1778)
						)
						(arc
							(start 0.2794 -0.1778)
							(mid 0.249642 -0.249642)
							(end 0.1778 -0.2794)
						)
					)
					(width 0)
					(fill yes)
				)
			)
		)
	)
	(footprint ""
		(layer "F.Cu")
		(at 7.949946 -443.900052 -90)
		(property "Reference" "LED1"
			(at 0 0 270)
			(layer "F.SilkS")
			(hide yes)
			(effects
				(font
					(size 1.27 1.27)
				)
			)
		)
		(property "Value" "LED-RB-6-GP"
			(at -4.6736 3.8354 270)
			(unlocked yes)
			(layer "F.Fab")
			(hide yes)
			(effects
				(font
					(size 1.016 1.016)
					(thickness 0.1524)
				)
			)
		)
		(property "Device Type" "LED-100-3P-067106H325"
			(at -4.6736 2.3114 270)
			(unlocked yes)
			(layer "F.Fab")
			(hide yes)
			(effects
				(font
					(size 1.016 1.016)
					(thickness 0.1524)
				)
			)
		)
		(duplicate_pad_numbers_are_jumpers no)
		(fp_line
			(start -1.7526 10.414)
			(end -1.7526 6.6548)
			(stroke
				(width 0.1524)
				(type default)
			)
			(layer "F.SilkS")
		)
		(fp_line
			(start 1.7526 10.414)
			(end -1.7526 10.414)
			(stroke
				(width 0.1524)
				(type default)
			)
			(layer "F.SilkS")
		)
		(fp_line
			(start -3.6068 6.6548)
			(end -3.6068 -0.889)
			(stroke
				(width 0.1524)
				(type default)
			)
			(layer "F.SilkS")
		)
		(fp_line
			(start -1.7526 6.6548)
			(end -3.6068 6.6548)
			(stroke
				(width 0.1524)
				(type default)
			)
			(layer "F.SilkS")
		)
		(fp_line
			(start 1.7526 6.6548)
			(end 1.7526 10.414)
			(stroke
				(width 0.1524)
				(type default)
			)
			(layer "F.SilkS")
		)
		(fp_line
			(start 3.6068 6.6548)
			(end 1.7526 6.6548)
			(stroke
				(width 0.1524)
				(type default)
			)
			(layer "F.SilkS")
		)
		(fp_line
			(start -3.6068 -0.889)
			(end 3.6068 -0.889)
			(stroke
				(width 0.1524)
				(type default)
			)
			(layer "F.SilkS")
		)
		(fp_line
			(start 3.6068 -0.889)
			(end 3.6068 6.6548)
			(stroke
				(width 0.1524)
				(type default)
			)
			(layer "F.SilkS")
		)
		(fp_circle
			(center -2.54 0)
			(end -2.54 -0.9906)
			(stroke
				(width 0.3048)
				(type default)
			)
			(fill no)
			(layer "F.SilkS")
		)
		(fp_circle
			(center 0 0)
			(end 0 -0.9906)
			(stroke
				(width 0.3048)
				(type default)
			)
			(fill no)
			(layer "F.SilkS")
		)
		(fp_circle
			(center 2.54 0)
			(end 2.54 -0.9906)
			(stroke
				(width 0.3048)
				(type default)
			)
			(fill no)
			(layer "F.SilkS")
		)
		(fp_poly
			(pts
				(xy -1.4986 10.1473) (xy -1.4986 6.4008) (xy -3.3528 6.4008) (xy -3.3528 -0.3937) (xy 3.3528 -0.3937)
				(xy 3.3528 6.4008) (xy 1.4986 6.4008) (xy 1.4986 10.1473)
			)
			(stroke
				(width 0)
				(type default)
			)
			(fill no)
			(layer "F.CrtYd")
		)
		(fp_poly
			(pts
				(xy -2.0066 10.668) (xy 2.0066 10.668) (xy 2.0066 6.9088) (xy 3.8608 6.9088) (xy 3.8608 2.2098)
				(xy 3.3528 2.2098) (xy 3.3528 6.4008) (xy 1.4986 6.4008) (xy 1.4986 10.1473) (xy -1.4986 10.1473)
				(xy -1.4986 6.4008) (xy -3.3528 6.4008) (xy -3.3528 -0.3937) (xy 3.3528 -0.3937) (xy 3.3528 2.1971)
				(xy 3.8608 2.1971) (xy 3.8608 -1.143) (xy -3.8608 -1.143) (xy -3.8608 6.9088) (xy -2.0066 6.9088)
			)
			(stroke
				(width 0)
				(type default)
			)
			(fill no)
			(layer "F.CrtYd")
		)
		(fp_poly
			(pts
				(xy -2.0066 10.668) (xy -2.0066 6.9088) (xy -3.8608 6.9088) (xy -3.8608 -1.143) (xy 3.8608 -1.143)
				(xy 3.8608 6.9088) (xy 2.0066 6.9088) (xy 2.0066 10.668)
			)
			(stroke
				(width 0)
				(type default)
			)
			(fill no)
			(layer "F.Fab")
		)
		(pad "1" thru_hole circle
			(at 2.54 0 270)
			(size 1.27 1.27)
			(drill 0.889)
			(layers "*.Cu" "*.Mask")
			(remove_unused_layers no)
			(net "LED_DR_LED0_BLUE")
			(clearance 0.1651)
			(thermal_gap 0.1651)
		)
		(pad "2" thru_hole circle
			(at 0 0 270)
			(size 1.27 1.27)
			(drill 0.889)
			(layers "*.Cu" "*.Mask")
			(remove_unused_layers no)
			(net "LED_DR_LED0_K")
			(clearance 0.1651)
			(thermal_gap 0.1651)
		)
		(pad "3" thru_hole circle
			(at -2.54 0 270)
			(size 1.27 1.27)
			(drill 0.889)
			(layers "*.Cu" "*.Mask")
			(remove_unused_layers no)
			(net "LED_DR_LED0")
			(clearance 0.1651)
			(thermal_gap 0.1651)
		)
	)
)
